(kicad_pcb
	(version 20260206)
	(generator "pcbnew")
	(generator_version "10.0")
	(general
		(thickness 1.6)
		(legacy_teardrops no)
	)
	(paper "A4")
	(title_block
		(title "dpb — 14545-sa.0730WZS0815.brd")
		(comment 1 "Honey Badger (Wiwynn) / footprints 144-151 of 1066")
	)
	(layers
		(0 "F.Cu" signal "TOP")
		(4 "In1.Cu" signal "L2GND")
		(6 "In2.Cu" signal "L3")
		(8 "In3.Cu" signal "L4VCC")
		(10 "In4.Cu" signal "L5VCC")
		(12 "In5.Cu" signal "L6")
		(14 "In6.Cu" signal "L7GND")
		(2 "B.Cu" signal "BOTTOM")
		(9 "F.Adhes" user "F.Adhesive")
		(11 "B.Adhes" user "B.Adhesive")
		(13 "F.Paste" user "Package Geometry/Pastemask Top")
		(15 "B.Paste" user "Package Geometry/Pastemask Bottom")
		(5 "F.SilkS" user "Ref Des/Silkscreen Top")
		(7 "B.SilkS" user "Ref Des/Silkscreen Bottom")
		(1 "F.Mask" user "Board Geometry/Soldermask Top")
		(3 "B.Mask" user "Board Geometry/Soldermask Bottom")
		(17 "Dwgs.User" user "User.Drawings")
		(19 "Cmts.User" user "User.Comments")
		(21 "Eco1.User" user "User.Eco1")
		(23 "Eco2.User" user "User.Eco2")
		(25 "Edge.Cuts" user "Board Geometry/Outline")
		(27 "Margin" user)
		(31 "F.CrtYd" user "Package Geometry/Place Bound Top")
		(29 "B.CrtYd" user "Package Geometry/Place Bound Bottom")
		(35 "F.Fab" user "Ref Des/Assembly Top")
		(33 "B.Fab" user "Ref Des/Assembly Bottom")
	)
	(footprint ""
		(layer "F.Cu")
		(at 197.103746 -183.9087 -90)
		(property "Reference" "R437"
			(at 0 0 270)
			(layer "F.SilkS")
			(hide yes)
			(effects
				(font
					(size 1.27 1.27)
				)
			)
		)
		(property "Value" "4K7R2J-2-GP"
			(at 0.064008 -3.993896 270)
			(unlocked yes)
			(layer "F.Fab")
			(hide yes)
			(effects
				(font
					(size 1.016 1.016)
					(thickness 0.1524)
				)
			)
		)
		(property "Device Type" "R402H16"
			(at 0.064008 -5.517896 270)
			(unlocked yes)
			(layer "F.Fab")
			(hide yes)
			(effects
				(font
					(size 1.016 1.016)
					(thickness 0.1524)
				)
			)
		)
		(duplicate_pad_numbers_are_jumpers no)
		(fp_line
			(start -0.508 -0.9398)
			(end -0.508 0.9398)
			(stroke
				(width 0.1524)
				(type default)
			)
			(layer "F.SilkS")
		)
		(fp_line
			(start 0.508 -0.9398)
			(end -0.508 -0.9398)
			(stroke
				(width 0.1524)
				(type default)
			)
			(layer "F.SilkS")
		)
		(fp_rect
			(start -0.508 0.9398)
			(end 0.508 -0.9398)
			(stroke
				(width 0)
				(type default)
			)
			(fill no)
			(layer "F.CrtYd")
		)
		(fp_rect
			(start -0.508 0.9398)
			(end 0.508 -0.9398)
			(stroke
				(width 0)
				(type default)
			)
			(fill no)
			(layer "F.Fab")
		)
		(pad "1" smd custom
			(at 0 -0.4445 270)
			(size 0.1397 0.1397)
			(layers "F.Cu" "F.Mask" "F.Paste")
			(net "P3V3")
			(options
				(clearance outline)
				(anchor circle)
			)
			(primitives
				(gr_poly
					(pts
						(arc
							(start -0.1778 -0.2794)
							(mid -0.249642 -0.249642)
							(end -0.2794 -0.1778)
						)
						(arc
							(start -0.2794 0.1778)
							(mid -0.249642 0.249642)
							(end -0.1778 0.2794)
						)
						(arc
							(start 0.1778 0.2794)
							(mid 0.249642 0.249642)
							(end 0.2794 0.1778)
						)
						(arc
							(start 0.2794 -0.1778)
							(mid 0.249642 -0.249642)
							(end 0.1778 -0.2794)
						)
					)
					(width 0)
					(fill yes)
				)
			)
		)
		(pad "2" smd custom
			(at 0 0.4445 270)
			(size 0.1397 0.1397)
			(layers "F.Cu" "F.Mask" "F.Paste")
			(net "SAS_EXP_B_PWR3")
			(options
				(clearance outline)
				(anchor circle)
			)
			(primitives
				(gr_poly
					(pts
						(arc
							(start -0.1778 -0.2794)
							(mid -0.249642 -0.249642)
							(end -0.2794 -0.1778)
						)
						(arc
							(start -0.2794 0.1778)
							(mid -0.249642 0.249642)
							(end -0.1778 0.2794)
						)
						(arc
							(start 0.1778 0.2794)
							(mid 0.249642 0.249642)
							(end 0.2794 0.1778)
						)
						(arc
							(start 0.2794 -0.1778)
							(mid 0.249642 -0.249642)
							(end 0.1778 -0.2794)
						)
					)
					(width 0)
					(fill yes)
				)
			)
		)
	)
	(footprint ""
		(layer "F.Cu")
		(at 217.346784 -180.183028 180)
		(property "Reference" "C154"
			(at 0 0 180)
			(layer "F.SilkS")
			(hide yes)
			(effects
				(font
					(size 1.27 1.27)
				)
			)
		)
		(property "Value" "SC1U16V3KX-5GP"
			(at 0 -2.8194 180)
			(unlocked yes)
			(layer "F.Fab")
			(hide yes)
			(effects
				(font
					(size 1.016 1.016)
					(thickness 0.1524)
				)
			)
		)
		(property "Device Type" "C603H36"
			(at 0 -4.3434 180)
			(unlocked yes)
			(layer "F.Fab")
			(hide yes)
			(effects
				(font
					(size 1.016 1.016)
					(thickness 0.1524)
				)
			)
		)
		(duplicate_pad_numbers_are_jumpers no)
		(fp_line
			(start 0.508 0)
			(end -0.508 0)
			(stroke
				(width 0.2032)
				(type default)
			)
			(layer "F.SilkS")
		)
		(fp_rect
			(start -0.5842 1.3335)
			(end 0.5842 -1.3335)
			(stroke
				(width 0)
				(type default)
			)
			(fill no)
			(layer "F.CrtYd")
		)
		(fp_rect
			(start -0.5842 1.3335)
			(end 0.5842 -1.3335)
			(stroke
				(width 0)
				(type default)
			)
			(fill no)
			(layer "F.Fab")
		)
		(pad "1" smd custom
			(at 0 -0.762 180)
			(size 0.2159 0.2159)
			(layers "F.Cu" "F.Mask" "F.Paste")
			(net "P5V_HDD3")
			(options
				(clearance outline)
				(anchor circle)
			)
			(primitives
				(gr_poly
					(pts
						(arc
							(start -0.3302 -0.4318)
							(mid -0.402042 -0.402042)
							(end -0.4318 -0.3302)
						)
						(arc
							(start -0.4318 0.3302)
							(mid -0.402042 0.402042)
							(end -0.3302 0.4318)
						)
						(arc
							(start 0.3302 0.4318)
							(mid 0.402042 0.402042)
							(end 0.4318 0.3302)
						)
						(arc
							(start 0.4318 -0.3302)
							(mid 0.402042 -0.402042)
							(end 0.3302 -0.4318)
						)
					)
					(width 0)
					(fill yes)
				)
			)
		)
		(pad "2" smd custom
			(at 0 0.762 180)
			(size 0.2159 0.2159)
			(layers "F.Cu" "F.Mask" "F.Paste")
			(net "GND")
			(options
				(clearance outline)
				(anchor circle)
			)
			(primitives
				(gr_poly
					(pts
						(arc
							(start -0.3302 -0.4318)
							(mid -0.402042 -0.402042)
							(end -0.4318 -0.3302)
						)
						(arc
							(start -0.4318 0.3302)
							(mid -0.402042 0.402042)
							(end -0.3302 0.4318)
						)
						(arc
							(start 0.3302 0.4318)
							(mid 0.402042 0.402042)
							(end 0.4318 0.3302)
						)
						(arc
							(start 0.4318 -0.3302)
							(mid 0.402042 -0.402042)
							(end 0.3302 -0.4318)
						)
					)
					(width 0)
					(fill yes)
				)
			)
		)
	)
	(footprint ""
		(layer "F.Cu")
		(at 10.8966 -153.1874 180)
		(property "Reference" "R545"
			(at 0 0 180)
			(layer "F.SilkS")
			(hide yes)
			(effects
				(font
					(size 1.27 1.27)
				)
			)
		)
		(property "Value" "0R2J-2-GP"
			(at 0.064008 -3.993896 180)
			(unlocked yes)
			(layer "F.Fab")
			(hide yes)
			(effects
				(font
					(size 1.016 1.016)
					(thickness 0.1524)
				)
			)
		)
		(property "Device Type" "R402H16"
			(at 0.064008 -5.517896 180)
			(unlocked yes)
			(layer "F.Fab")
			(hide yes)
			(effects
				(font
					(size 1.016 1.016)
					(thickness 0.1524)
				)
			)
		)
		(duplicate_pad_numbers_are_jumpers no)
		(fp_line
			(start 0.508 -0.9398)
			(end -0.508 -0.9398)
			(stroke
				(width 0.1524)
				(type default)
			)
			(layer "F.SilkS")
		)
		(fp_line
			(start -0.508 -0.9398)
			(end -0.508 0.9398)
			(stroke
				(width 0.1524)
				(type default)
			)
			(layer "F.SilkS")
		)
		(fp_rect
			(start -0.508 0.9398)
			(end 0.508 -0.9398)
			(stroke
				(width 0)
				(type default)
			)
			(fill no)
			(layer "F.CrtYd")
		)
		(fp_rect
			(start -0.508 0.9398)
			(end 0.508 -0.9398)
			(stroke
				(width 0)
				(type default)
			)
			(fill no)
			(layer "F.Fab")
		)
		(pad "1" smd custom
			(at 0 -0.4445 180)
			(size 0.1397 0.1397)
			(layers "F.Cu" "F.Mask" "F.Paste")
			(net "I2C_B_SDA_DAMP_B")
			(options
				(clearance outline)
				(anchor circle)
			)
			(primitives
				(gr_poly
					(pts
						(arc
							(start -0.1778 -0.2794)
							(mid -0.249642 -0.249642)
							(end -0.2794 -0.1778)
						)
						(arc
							(start -0.2794 0.1778)
							(mid -0.249642 0.249642)
							(end -0.1778 0.2794)
						)
						(arc
							(start 0.1778 0.2794)
							(mid 0.249642 0.249642)
							(end 0.2794 0.1778)
						)
						(arc
							(start 0.2794 -0.1778)
							(mid 0.249642 -0.249642)
							(end 0.1778 -0.2794)
						)
					)
					(width 0)
					(fill yes)
				)
			)
		)
		(pad "2" smd custom
			(at 0 0.4445 180)
			(size 0.1397 0.1397)
			(layers "F.Cu" "F.Mask" "F.Paste")
			(net "I2C_B_SDA")
			(options
				(clearance outline)
				(anchor circle)
			)
			(primitives
				(gr_poly
					(pts
						(arc
							(start -0.1778 -0.2794)
							(mid -0.249642 -0.249642)
							(end -0.2794 -0.1778)
						)
						(arc
							(start -0.2794 0.1778)
							(mid -0.249642 0.249642)
							(end -0.1778 0.2794)
						)
						(arc
							(start 0.1778 0.2794)
							(mid 0.249642 0.249642)
							(end 0.2794 0.1778)
						)
						(arc
							(start 0.2794 -0.1778)
							(mid 0.249642 -0.249642)
							(end 0.1778 -0.2794)
						)
					)
					(width 0)
					(fill yes)
				)
			)
		)
	)
	(footprint ""
		(layer "F.Cu")
		(at 42.500042 -41.159938 180)
		(property "Reference" "LED10"
			(at 0 0 180)
			(layer "F.SilkS")
			(hide yes)
			(effects
				(font
					(size 1.27 1.27)
				)
			)
		)
		(property "Value" "LED-RB-4-GP"
			(at 5.88899 1.80848 180)
			(unlocked yes)
			(layer "F.Fab")
			(hide yes)
			(effects
				(font
					(size 1.016 1.016)
					(thickness 0.1524)
				)
			)
		)
		(property "Device Type" "LED1613-4PH20"
			(at 5.88899 0.28448 180)
			(unlocked yes)
			(layer "F.Fab")
			(hide yes)
			(effects
				(font
					(size 1.016 1.016)
					(thickness 0.1524)
				)
			)
		)
		(duplicate_pad_numbers_are_jumpers no)
		(fp_line
			(start 1.4478 0.9652)
			(end -1.4478 0.9652)
			(stroke
				(width 0.1524)
				(type default)
			)
			(layer "F.SilkS")
		)
		(fp_line
			(start 1.4478 -0.9652)
			(end 1.4478 0.9652)
			(stroke
				(width 0.1524)
				(type default)
			)
			(layer "F.SilkS")
		)
		(fp_line
			(start -1.4478 0.9652)
			(end -1.4478 -0.9652)
			(stroke
				(width 0.1524)
				(type default)
			)
			(layer "F.SilkS")
		)
		(fp_line
			(start -1.4478 0.9652)
			(end -1.4478 -0.9652)
			(stroke
				(width 0.508)
				(type default)
			)
			(layer "F.SilkS")
		)
		(fp_line
			(start -1.4478 -0.9652)
			(end 1.4478 -0.9652)
			(stroke
				(width 0.1524)
				(type default)
			)
			(layer "F.SilkS")
		)
		(fp_rect
			(start -0.8001 0.6477)
			(end 0.8001 -0.6477)
			(stroke
				(width 0)
				(type default)
			)
			(fill no)
			(layer "F.CrtYd")
		)
		(fp_poly
			(pts
				(xy -1.7018 1.2192) (xy -1.7018 -0.06223) (xy -0.8001 -0.06223) (xy -0.8001 0.6477) (xy 0.8001 0.6477)
				(xy 0.8001 -0.6477) (xy -0.8001 -0.6477) (xy -0.8001 -0.0635) (xy -1.7018 -0.0635) (xy -1.7018 -1.2192)
				(xy 1.7018 -1.2192) (xy 1.7018 1.2192)
			)
			(stroke
				(width 0)
				(type default)
			)
			(fill no)
			(layer "F.CrtYd")
		)
		(fp_rect
			(start -1.7018 1.2192)
			(end 1.7018 -1.2192)
			(stroke
				(width 0)
				(type default)
			)
			(fill no)
			(layer "F.Fab")
		)
		(pad "1" smd rect
			(at -0.73025 0.4064 180)
			(size 0.9144 0.6096)
			(layers "F.Cu" "F.Mask" "F.Paste")
			(net "DRV_ACT_NET9")
		)
		(pad "2" smd rect
			(at -0.73025 -0.4064 180)
			(size 0.9144 0.6096)
			(layers "F.Cu" "F.Mask" "F.Paste")
			(net "FLT_NET_HDD9")
		)
		(pad "3" smd rect
			(at 0.73025 -0.4064 180)
			(size 0.9144 0.6096)
			(layers "F.Cu" "F.Mask" "F.Paste")
			(net "FLT_HDD9")
		)
		(pad "4" smd rect
			(at 0.73025 0.4064 180)
			(size 0.9144 0.6096)
			(layers "F.Cu" "F.Mask" "F.Paste")
			(net "DRV_ACT_9")
		)
	)
	(footprint ""
		(layer "F.Cu")
		(at 29.082746 -329.720702 -90)
		(property "Reference" "R261"
			(at 0 0 270)
			(layer "F.SilkS")
			(hide yes)
			(effects
				(font
					(size 1.27 1.27)
				)
			)
		)
		(property "Value" "4K7R2J-2-GP"
			(at 0.064008 -3.993896 270)
			(unlocked yes)
			(layer "F.Fab")
			(hide yes)
			(effects
				(font
					(size 1.016 1.016)
					(thickness 0.1524)
				)
			)
		)
		(property "Device Type" "R402H16"
			(at 0.064008 -5.517896 270)
			(unlocked yes)
			(layer "F.Fab")
			(hide yes)
			(effects
				(font
					(size 1.016 1.016)
					(thickness 0.1524)
				)
			)
		)
		(duplicate_pad_numbers_are_jumpers no)
		(fp_line
			(start -0.508 -0.9398)
			(end -0.508 0.9398)
			(stroke
				(width 0.1524)
				(type default)
			)
			(layer "F.SilkS")
		)
		(fp_line
			(start 0.508 -0.9398)
			(end -0.508 -0.9398)
			(stroke
				(width 0.1524)
				(type default)
			)
			(layer "F.SilkS")
		)
		(fp_rect
			(start -0.508 0.9398)
			(end 0.508 -0.9398)
			(stroke
				(width 0)
				(type default)
			)
			(fill no)
			(layer "F.CrtYd")
		)
		(fp_rect
			(start -0.508 0.9398)
			(end 0.508 -0.9398)
			(stroke
				(width 0)
				(type default)
			)
			(fill no)
			(layer "F.Fab")
		)
		(pad "1" smd custom
			(at 0 -0.4445 270)
			(size 0.1397 0.1397)
			(layers "F.Cu" "F.Mask" "F.Paste")
			(net "P3V3")
			(options
				(clearance outline)
				(anchor circle)
			)
			(primitives
				(gr_poly
					(pts
						(arc
							(start -0.1778 -0.2794)
							(mid -0.249642 -0.249642)
							(end -0.2794 -0.1778)
						)
						(arc
							(start -0.2794 0.1778)
							(mid -0.249642 0.249642)
							(end -0.1778 0.2794)
						)
						(arc
							(start 0.1778 0.2794)
							(mid 0.249642 0.249642)
							(end 0.2794 0.1778)
						)
						(arc
							(start 0.2794 -0.1778)
							(mid 0.249642 -0.249642)
							(end 0.1778 -0.2794)
						)
					)
					(width 0)
					(fill yes)
				)
			)
		)
		(pad "2" smd custom
			(at 0 0.4445 270)
			(size 0.1397 0.1397)
			(layers "F.Cu" "F.Mask" "F.Paste")
			(net "HDD_PRSNT_NET11")
			(options
				(clearance outline)
				(anchor circle)
			)
			(primitives
				(gr_poly
					(pts
						(arc
							(start -0.1778 -0.2794)
							(mid -0.249642 -0.249642)
							(end -0.2794 -0.1778)
						)
						(arc
							(start -0.2794 0.1778)
							(mid -0.249642 0.249642)
							(end -0.1778 0.2794)
						)
						(arc
							(start 0.1778 0.2794)
							(mid 0.249642 0.249642)
							(end 0.2794 0.1778)
						)
						(arc
							(start 0.2794 -0.1778)
							(mid 0.249642 -0.249642)
							(end 0.1778 -0.2794)
						)
					)
					(width 0)
					(fill yes)
				)
			)
		)
	)
	(footprint ""
		(layer "F.Cu")
		(at 240.2586 -377.6726 -90)
		(property "Reference" "C348"
			(at 0 0 270)
			(layer "F.SilkS")
			(hide yes)
			(effects
				(font
					(size 1.27 1.27)
				)
			)
		)
		(property "Value" "SC10U25V6KX-1GP"
			(at -0.0762 -5.1308 270)
			(unlocked yes)
			(layer "F.Fab")
			(hide yes)
			(effects
				(font
					(size 1.016 1.016)
					(thickness 0.1524)
				)
			)
		)
		(property "Device Type" "C1206H71"
			(at -0.127 -6.6548 270)
			(unlocked yes)
			(layer "F.Fab")
			(hide yes)
			(effects
				(font
					(size 1.016 1.016)
					(thickness 0.1524)
				)
			)
		)
		(duplicate_pad_numbers_are_jumpers no)
		(fp_line
			(start -1.016 2.2352)
			(end -1.016 0.8382)
			(stroke
				(width 0.1524)
				(type default)
			)
			(layer "F.SilkS")
		)
		(fp_line
			(start 1.016 2.2352)
			(end -1.016 2.2352)
			(stroke
				(width 0.1524)
				(type default)
			)
			(layer "F.SilkS")
		)
		(fp_line
			(start 1.016 0.8382)
			(end 1.016 2.2352)
			(stroke
				(width 0.1524)
				(type default)
			)
			(layer "F.SilkS")
		)
		(fp_line
			(start -1.016 -0.8382)
			(end -1.016 -2.2352)
			(stroke
				(width 0.1524)
				(type default)
			)
			(layer "F.SilkS")
		)
		(fp_line
			(start -1.016 -2.2352)
			(end 1.016 -2.2352)
			(stroke
				(width 0.1524)
				(type default)
			)
			(layer "F.SilkS")
		)
		(fp_line
			(start 1.016 -2.2352)
			(end 1.016 -0.8382)
			(stroke
				(width 0.1524)
				(type default)
			)
			(layer "F.SilkS")
		)
		(fp_rect
			(start -1.0922 2.3114)
			(end 1.0922 -2.3114)
			(stroke
				(width 0)
				(type default)
			)
			(fill no)
			(layer "F.CrtYd")
		)
		(fp_poly
			(pts
				(xy 1.0922 -2.3114) (xy 1.0922 2.3114) (xy -1.0922 2.3114) (xy -1.0922 -2.3114)
			)
			(stroke
				(width 0)
				(type default)
			)
			(fill no)
			(layer "F.Fab")
		)
		(pad "1" smd rect
			(at 0 -1.397 270)
			(size 1.651 1.27)
			(layers "F.Cu" "F.Mask" "F.Paste")
			(net "P12V")
		)
		(pad "2" smd rect
			(at 0 1.397 270)
			(size 1.651 1.27)
			(layers "F.Cu" "F.Mask" "F.Paste")
			(net "GND")
		)
	)
	(footprint ""
		(layer "F.Cu")
		(at 38.099746 -116.487702)
		(property "Reference" "C319"
			(at 0 0 0)
			(layer "F.SilkS")
			(hide yes)
			(effects
				(font
					(size 1.27 1.27)
				)
			)
		)
		(property "Value" "SC10U25V6KX-1GP"
			(at -0.0762 -5.1308 0)
			(unlocked yes)
			(layer "F.Fab")
			(hide yes)
			(effects
				(font
					(size 1.016 1.016)
					(thickness 0.1524)
				)
			)
		)
		(property "Device Type" "C1206H71"
			(at -0.127 -6.6548 0)
			(unlocked yes)
			(layer "F.Fab")
			(hide yes)
			(effects
				(font
					(size 1.016 1.016)
					(thickness 0.1524)
				)
			)
		)
		(duplicate_pad_numbers_are_jumpers no)
		(fp_line
			(start -1.016 -2.2352)
			(end 1.016 -2.2352)
			(stroke
				(width 0.1524)
				(type default)
			)
			(layer "F.SilkS")
		)
		(fp_line
			(start -1.016 -0.8382)
			(end -1.016 -2.2352)
			(stroke
				(width 0.1524)
				(type default)
			)
			(layer "F.SilkS")
		)
		(fp_line
			(start -1.016 2.2352)
			(end -1.016 0.8382)
			(stroke
				(width 0.1524)
				(type default)
			)
			(layer "F.SilkS")
		)
		(fp_line
			(start 1.016 -2.2352)
			(end 1.016 -0.8382)
			(stroke
				(width 0.1524)
				(type default)
			)
			(layer "F.SilkS")
		)
		(fp_line
			(start 1.016 0.8382)
			(end 1.016 2.2352)
			(stroke
				(width 0.1524)
				(type default)
			)
			(layer "F.SilkS")
		)
		(fp_line
			(start 1.016 2.2352)
			(end -1.016 2.2352)
			(stroke
				(width 0.1524)
				(type default)
			)
			(layer "F.SilkS")
		)
		(fp_rect
			(start -1.0922 2.3114)
			(end 1.0922 -2.3114)
			(stroke
				(width 0)
				(type default)
			)
			(fill no)
			(layer "F.CrtYd")
		)
		(fp_poly
			(pts
				(xy 1.0922 -2.3114) (xy 1.0922 2.3114) (xy -1.0922 2.3114) (xy -1.0922 -2.3114)
			)
			(stroke
				(width 0)
				(type default)
			)
			(fill no)
			(layer "F.Fab")
		)
		(pad "1" smd rect
			(at 0 -1.397)
			(size 1.651 1.27)
			(layers "F.Cu" "F.Mask" "F.Paste")
			(net "P12V_HDD13")
		)
		(pad "2" smd rect
			(at 0 1.397)
			(size 1.651 1.27)
			(layers "F.Cu" "F.Mask" "F.Paste")
			(net "GND")
		)
	)
	(footprint ""
		(layer "F.Cu")
		(at 58.419746 -191.7827 180)
		(property "Reference" "C241"
			(at 0 0 180)
			(layer "F.SilkS")
			(hide yes)
			(effects
				(font
					(size 1.27 1.27)
				)
			)
		)
		(property "Value" "SC10U25V6KX-1GP"
			(at -0.0762 -5.1308 180)
			(unlocked yes)
			(layer "F.Fab")
			(hide yes)
			(effects
				(font
					(size 1.016 1.016)
					(thickness 0.1524)
				)
			)
		)
		(property "Device Type" "C1206H71"
			(at -0.127 -6.6548 180)
			(unlocked yes)
			(layer "F.Fab")
			(hide yes)
			(effects
				(font
					(size 1.016 1.016)
					(thickness 0.1524)
				)
			)
		)
		(duplicate_pad_numbers_are_jumpers no)
		(fp_line
			(start 1.016 2.2352)
			(end -1.016 2.2352)
			(stroke
				(width 0.1524)
				(type default)
			)
			(layer "F.SilkS")
		)
		(fp_line
			(start 1.016 0.8382)
			(end 1.016 2.2352)
			(stroke
				(width 0.1524)
				(type default)
			)
			(layer "F.SilkS")
		)
		(fp_line
			(start 1.016 -2.2352)
			(end 1.016 -0.8382)
			(stroke
				(width 0.1524)
				(type default)
			)
			(layer "F.SilkS")
		)
		(fp_line
			(start -1.016 2.2352)
			(end -1.016 0.8382)
			(stroke
				(width 0.1524)
				(type default)
			)
			(layer "F.SilkS")
		)
		(fp_line
			(start -1.016 -0.8382)
			(end -1.016 -2.2352)
			(stroke
				(width 0.1524)
				(type default)
			)
			(layer "F.SilkS")
		)
		(fp_line
			(start -1.016 -2.2352)
			(end 1.016 -2.2352)
			(stroke
				(width 0.1524)
				(type default)
			)
			(layer "F.SilkS")
		)
		(fp_rect
			(start -1.0922 2.3114)
			(end 1.0922 -2.3114)
			(stroke
				(width 0)
				(type default)
			)
			(fill no)
			(layer "F.CrtYd")
		)
		(fp_poly
			(pts
				(xy 1.0922 -2.3114) (xy 1.0922 2.3114) (xy -1.0922 2.3114) (xy -1.0922 -2.3114)
			)
			(stroke
				(width 0)
				(type default)
			)
			(fill no)
			(layer "F.Fab")
		)
		(pad "1" smd rect
			(at 0 -1.397 180)
			(size 1.651 1.27)
			(layers "F.Cu" "F.Mask" "F.Paste")
			(net "P12V_HDD8")
		)
		(pad "2" smd rect
			(at 0 1.397 180)
			(size 1.651 1.27)
			(layers "F.Cu" "F.Mask" "F.Paste")
			(net "GND")
		)
	)
)
